# S9S_MB_2U (Grand Teton) — schematic netlist excerpt (pin names and nets, part order shuffled) for the footprints in the layout excerpt that follows; sources: Cadence DE-HDL packaged netlist, KiCad conversion of 03242023_DA0F0TMBIJ0_F0T_Motherboard_J_brd_V01_OCP.brd

R2919  Q_RES  4.7K 5% CHIP  pkg 0402LF  page 148 : A = P3V3_AUX ; B = RST_BMC_FROM_SWB_ISO_N
R1654  Q_RES  1K 1% CHIP  pkg 0402LF  page 260 : A = VR_P5V_EN_D_R ; B = VR_P5V_EN_D_R1

(kicad_pcb
	(version 20260206)
	(generator "pcbnew")
	(generator_version "10.0")
	(general
		(thickness 1.6)
		(legacy_teardrops no)
	)
	(paper "A4")
	(title_block
		(title "03242023_DA0F0TMBIJ0_F0T_Motherboard_J_brd_V01_OCP.brd")
		(comment 1 "Grand Teton / footprints 3423-3424 of 6105")
	)
	(layers
		(0 "F.Cu" signal "TOP")
		(4 "In1.Cu" signal "GND")
		(6 "In2.Cu" signal "IN1")
		(8 "In3.Cu" signal "GND1")
		(10 "In4.Cu" signal "IN2")
		(12 "In5.Cu" signal "GND2")
		(14 "In6.Cu" signal "IN3")
		(16 "In7.Cu" signal "GND3")
		(18 "In8.Cu" signal "VCC")
		(20 "In9.Cu" signal "VCC1")
		(22 "In10.Cu" signal "GND4")
		(24 "In11.Cu" signal "IN4")
		(26 "In12.Cu" signal "GND5")
		(28 "In13.Cu" signal "IN5")
		(30 "In14.Cu" signal "GND6")
		(32 "In15.Cu" signal "IN6")
		(34 "In16.Cu" signal "GND7")
		(2 "B.Cu" signal "BOTTOM")
		(9 "F.Adhes" user "F.Adhesive")
		(11 "B.Adhes" user "B.Adhesive")
		(13 "F.Paste" user "Package Geometry/Pastemask Top")
		(15 "B.Paste" user "Package Geometry/Pastemask Bottom")
		(5 "F.SilkS" user "Ref Des/Silkscreen Top")
		(7 "B.SilkS" user "Ref Des/Silkscreen Bottom")
		(1 "F.Mask" user "Board Geometry/Soldermask Top")
		(3 "B.Mask" user "Board Geometry/Soldermask Bottom")
		(17 "Dwgs.User" user "User.Drawings")
		(19 "Cmts.User" user "User.Comments")
		(21 "Eco1.User" user "User.Eco1")
		(23 "Eco2.User" user "User.Eco2")
		(25 "Edge.Cuts" user "Board Geometry/Outline")
		(27 "Margin" user)
		(31 "F.CrtYd" user "Package Geometry/Place Bound Top")
		(29 "B.CrtYd" user "Package Geometry/Place Bound Bottom")
		(35 "F.Fab" user "Ref Des/Assembly Top")
		(33 "B.Fab" user "Ref Des/Assembly Bottom")
	)
	(footprint ""
		(layer "F.Cu")
		(at 424.204892 -379.313948)
		(property "Reference" "R2919"
			(at 0 0 0)
			(layer "F.SilkS")
			(hide yes)
			(effects
				(font
					(size 1.27 1.27)
				)
			)
		)
		(property "Value" ""
			(at 0 0 0)
			(layer "F.Fab")
			(effects
				(font
					(size 1.27 1.27)
				)
			)
		)
		(duplicate_pad_numbers_are_jumpers no)
		(fp_line
			(start -0.7874 -0.4064)
			(end 0.7874 -0.4064)
			(stroke
				(width 0.1524)
				(type default)
			)
			(layer "F.SilkS")
		)
		(fp_line
			(start -0.7874 0.4064)
			(end -0.7874 -0.4064)
			(stroke
				(width 0.1524)
				(type default)
			)
			(layer "F.SilkS")
		)
		(fp_line
			(start 0.7874 -0.4064)
			(end 0.7874 0.4064)
			(stroke
				(width 0.1524)
				(type default)
			)
			(layer "F.SilkS")
		)
		(fp_line
			(start 0.7874 0.4064)
			(end -0.7874 0.4064)
			(stroke
				(width 0.1524)
				(type default)
			)
			(layer "F.SilkS")
		)
		(fp_line
			(start -0.67945 -0.305054)
			(end -0.12065 -0.305054)
			(stroke
				(width 0.1)
				(type default)
			)
			(layer "F.Fab")
		)
		(fp_line
			(start -0.67945 0.3048)
			(end -0.67945 -0.305054)
			(stroke
				(width 0.1)
				(type default)
			)
			(layer "F.Fab")
		)
		(fp_line
			(start -0.12065 -0.305054)
			(end -0.12065 -0.2794)
			(stroke
				(width 0.1)
				(type default)
			)
			(layer "F.Fab")
		)
		(fp_line
			(start -0.12065 -0.2794)
			(end 0.12065 -0.2794)
			(stroke
				(width 0.1)
				(type default)
			)
			(layer "F.Fab")
		)
		(fp_line
			(start -0.12065 0.2794)
			(end -0.12065 0.3048)
			(stroke
				(width 0.1)
				(type default)
			)
			(layer "F.Fab")
		)
		(fp_line
			(start -0.12065 0.3048)
			(end -0.67945 0.3048)
			(stroke
				(width 0.1)
				(type default)
			)
			(layer "F.Fab")
		)
		(fp_line
			(start 0.120396 0.2794)
			(end -0.12065 0.2794)
			(stroke
				(width 0.1)
				(type default)
			)
			(layer "F.Fab")
		)
		(fp_line
			(start 0.120396 0.3048)
			(end 0.120396 0.2794)
			(stroke
				(width 0.1)
				(type default)
			)
			(layer "F.Fab")
		)
		(fp_line
			(start 0.12065 -0.3048)
			(end 0.67945 -0.3048)
			(stroke
				(width 0.1)
				(type default)
			)
			(layer "F.Fab")
		)
		(fp_line
			(start 0.12065 -0.2794)
			(end 0.12065 -0.3048)
			(stroke
				(width 0.1)
				(type default)
			)
			(layer "F.Fab")
		)
		(fp_line
			(start 0.67945 -0.3048)
			(end 0.67945 0.3048)
			(stroke
				(width 0.1)
				(type default)
			)
			(layer "F.Fab")
		)
		(fp_line
			(start 0.67945 0.3048)
			(end 0.120396 0.3048)
			(stroke
				(width 0.1)
				(type default)
			)
			(layer "F.Fab")
		)
		(pad "1" smd circle
			(at -0.40005 0)
			(size 0 0)
			(layers "F.Cu" "F.Mask" "F.Paste")
			(net "P3V3_AUX")
		)
		(pad "2" smd circle
			(at 0.40005 0)
			(size 0 0)
			(layers "F.Cu" "F.Mask" "F.Paste")
			(net "RST_BMC_FROM_SWB_ISO_N")
		)
	)
	(footprint ""
		(layer "F.Cu")
		(at 165.301676 -131.980178 -90)
		(property "Reference" "R1654"
			(at 0 0 270)
			(layer "F.SilkS")
			(hide yes)
			(effects
				(font
					(size 1.27 1.27)
				)
			)
		)
		(property "Value" ""
			(at 0 0 270)
			(layer "F.Fab")
			(effects
				(font
					(size 1.27 1.27)
				)
			)
		)
		(duplicate_pad_numbers_are_jumpers no)
		(fp_line
			(start -0.7874 0.4064)
			(end -0.7874 -0.4064)
			(stroke
				(width 0.1524)
				(type default)
			)
			(layer "F.SilkS")
		)
		(fp_line
			(start 0.7874 0.4064)
			(end -0.7874 0.4064)
			(stroke
				(width 0.1524)
				(type default)
			)
			(layer "F.SilkS")
		)
		(fp_line
			(start -0.7874 -0.4064)
			(end 0.7874 -0.4064)
			(stroke
				(width 0.1524)
				(type default)
			)
			(layer "F.SilkS")
		)
		(fp_line
			(start 0.7874 -0.4064)
			(end 0.7874 0.4064)
			(stroke
				(width 0.1524)
				(type default)
			)
			(layer "F.SilkS")
		)
		(fp_line
			(start -0.67945 0.3048)
			(end -0.67945 -0.305054)
			(stroke
				(width 0.1)
				(type default)
			)
			(layer "F.Fab")
		)
		(fp_line
			(start -0.12065 0.3048)
			(end -0.67945 0.3048)
			(stroke
				(width 0.1)
				(type default)
			)
			(layer "F.Fab")
		)
		(fp_line
			(start 0.120396 0.3048)
			(end 0.120396 0.2794)
			(stroke
				(width 0.1)
				(type default)
			)
			(layer "F.Fab")
		)
		(fp_line
			(start 0.67945 0.3048)
			(end 0.120396 0.3048)
			(stroke
				(width 0.1)
				(type default)
			)
			(layer "F.Fab")
		)
		(fp_line
			(start -0.12065 0.2794)
			(end -0.12065 0.3048)
			(stroke
				(width 0.1)
				(type default)
			)
			(layer "F.Fab")
		)
		(fp_line
			(start 0.120396 0.2794)
			(end -0.12065 0.2794)
			(stroke
				(width 0.1)
				(type default)
			)
			(layer "F.Fab")
		)
		(fp_line
			(start -0.12065 -0.2794)
			(end 0.12065 -0.2794)
			(stroke
				(width 0.1)
				(type default)
			)
			(layer "F.Fab")
		)
		(fp_line
			(start 0.12065 -0.2794)
			(end 0.12065 -0.3048)
			(stroke
				(width 0.1)
				(type default)
			)
			(layer "F.Fab")
		)
		(fp_line
			(start 0.12065 -0.3048)
			(end 0.67945 -0.3048)
			(stroke
				(width 0.1)
				(type default)
			)
			(layer "F.Fab")
		)
		(fp_line
			(start 0.67945 -0.3048)
			(end 0.67945 0.3048)
			(stroke
				(width 0.1)
				(type default)
			)
			(layer "F.Fab")
		)
		(fp_line
			(start -0.67945 -0.305054)
			(end -0.12065 -0.305054)
			(stroke
				(width 0.1)
				(type default)
			)
			(layer "F.Fab")
		)
		(fp_line
			(start -0.12065 -0.305054)
			(end -0.12065 -0.2794)
			(stroke
				(width 0.1)
				(type default)
			)
			(layer "F.Fab")
		)
		(pad "1" smd circle
			(at -0.40005 0 270)
			(size 0 0)
			(layers "F.Cu" "F.Mask" "F.Paste")
			(net "VR_P5V_EN_D_R")
		)
		(pad "2" smd circle
			(at 0.40005 0 270)
			(size 0 0)
			(layers "F.Cu" "F.Mask" "F.Paste")
			(net "VR_P5V_EN_D_R1")
		)
	)
)
